(kicad_pcb
	(version 20260206)
	(generator "pcbnew")
	(generator_version "10.0")
	(general
		(thickness 1.6)
		(legacy_teardrops no)
	)
	(paper "A4")
	(title_block
		(title "01162023_DA0F0TEBIF0_F0T_Expander_BD_F_brd_V02_OCP.brd")
		(comment 1 "Grand Teton / footprints 1976-1980 of 9728")
	)
	(layers
		(0 "F.Cu" signal "TOP")
		(4 "In1.Cu" signal "GND")
		(6 "In2.Cu" signal "VCC")
		(8 "In3.Cu" signal "VCC1")
		(10 "In4.Cu" signal "GND1")
		(12 "In5.Cu" signal "IN1")
		(14 "In6.Cu" signal "GND2")
		(16 "In7.Cu" signal "IN2")
		(18 "In8.Cu" signal "GND3")
		(20 "In9.Cu" signal "IN3")
		(22 "In10.Cu" signal "GND4")
		(24 "In11.Cu" signal "IN4")
		(26 "In12.Cu" signal "GND5")
		(28 "In13.Cu" signal "IN5")
		(30 "In14.Cu" signal "GND6")
		(32 "In15.Cu" signal "IN6")
		(34 "In16.Cu" signal "GND7")
		(2 "B.Cu" signal "BOTTOM")
		(9 "F.Adhes" user "F.Adhesive")
		(11 "B.Adhes" user "B.Adhesive")
		(13 "F.Paste" user "Package Geometry/Pastemask Top")
		(15 "B.Paste" user "Package Geometry/Pastemask Bottom")
		(5 "F.SilkS" user "Ref Des/Silkscreen Top")
		(7 "B.SilkS" user "Ref Des/Silkscreen Bottom")
		(1 "F.Mask" user "Board Geometry/Soldermask Top")
		(3 "B.Mask" user "Board Geometry/Soldermask Bottom")
		(17 "Dwgs.User" user "User.Drawings")
		(19 "Cmts.User" user "User.Comments")
		(21 "Eco1.User" user "User.Eco1")
		(23 "Eco2.User" user "User.Eco2")
		(25 "Edge.Cuts" user "Board Geometry/Outline")
		(27 "Margin" user)
		(31 "F.CrtYd" user "Package Geometry/Place Bound Top")
		(29 "B.CrtYd" user "Package Geometry/Place Bound Bottom")
		(35 "F.Fab" user "Ref Des/Assembly Top")
		(33 "B.Fab" user "Ref Des/Assembly Bottom")
	)
	(footprint ""
		(layer "F.Cu")
		(at 6.914388 -365.792258 90)
		(property "Reference" "R6758"
			(at 0 0 90)
			(layer "F.SilkS")
			(hide yes)
			(effects
				(font
					(size 1.27 1.27)
				)
			)
		)
		(property "Value" ""
			(at 0 0 90)
			(layer "F.Fab")
			(effects
				(font
					(size 1.27 1.27)
				)
			)
		)
		(duplicate_pad_numbers_are_jumpers no)
		(fp_line
			(start 0.7874 -0.4064)
			(end 0.7874 0.4064)
			(stroke
				(width 0.1524)
				(type default)
			)
			(layer "F.SilkS")
		)
		(fp_line
			(start -0.7874 -0.4064)
			(end 0.7874 -0.4064)
			(stroke
				(width 0.1524)
				(type default)
			)
			(layer "F.SilkS")
		)
		(fp_line
			(start 0.7874 0.4064)
			(end -0.7874 0.4064)
			(stroke
				(width 0.1524)
				(type default)
			)
			(layer "F.SilkS")
		)
		(fp_line
			(start -0.7874 0.4064)
			(end -0.7874 -0.4064)
			(stroke
				(width 0.1524)
				(type default)
			)
			(layer "F.SilkS")
		)
		(fp_line
			(start -0.12065 -0.305054)
			(end -0.12065 -0.2794)
			(stroke
				(width 0.1)
				(type default)
			)
			(layer "F.Fab")
		)
		(fp_line
			(start -0.67945 -0.305054)
			(end -0.12065 -0.305054)
			(stroke
				(width 0.1)
				(type default)
			)
			(layer "F.Fab")
		)
		(fp_line
			(start 0.67945 -0.3048)
			(end 0.67945 0.3048)
			(stroke
				(width 0.1)
				(type default)
			)
			(layer "F.Fab")
		)
		(fp_line
			(start 0.12065 -0.3048)
			(end 0.67945 -0.3048)
			(stroke
				(width 0.1)
				(type default)
			)
			(layer "F.Fab")
		)
		(fp_line
			(start 0.12065 -0.2794)
			(end 0.12065 -0.3048)
			(stroke
				(width 0.1)
				(type default)
			)
			(layer "F.Fab")
		)
		(fp_line
			(start -0.12065 -0.2794)
			(end 0.12065 -0.2794)
			(stroke
				(width 0.1)
				(type default)
			)
			(layer "F.Fab")
		)
		(fp_line
			(start 0.120396 0.2794)
			(end -0.12065 0.2794)
			(stroke
				(width 0.1)
				(type default)
			)
			(layer "F.Fab")
		)
		(fp_line
			(start -0.12065 0.2794)
			(end -0.12065 0.3048)
			(stroke
				(width 0.1)
				(type default)
			)
			(layer "F.Fab")
		)
		(fp_line
			(start 0.67945 0.3048)
			(end 0.120396 0.3048)
			(stroke
				(width 0.1)
				(type default)
			)
			(layer "F.Fab")
		)
		(fp_line
			(start 0.120396 0.3048)
			(end 0.120396 0.2794)
			(stroke
				(width 0.1)
				(type default)
			)
			(layer "F.Fab")
		)
		(fp_line
			(start -0.12065 0.3048)
			(end -0.67945 0.3048)
			(stroke
				(width 0.1)
				(type default)
			)
			(layer "F.Fab")
		)
		(fp_line
			(start -0.67945 0.3048)
			(end -0.67945 -0.305054)
			(stroke
				(width 0.1)
				(type default)
			)
			(layer "F.Fab")
		)
		(pad "1" smd circle
			(at -0.40005 0 90)
			(size 0 0)
			(layers "F.Cu" "F.Mask" "F.Paste")
			(net "P3V3_AUX")
		)
		(pad "2" smd circle
			(at 0.40005 0 90)
			(size 0 0)
			(layers "F.Cu" "F.Mask" "F.Paste")
			(net "PG12_USB_HUB_N")
		)
	)
	(footprint ""
		(layer "F.Cu")
		(at 325.20382 -291.722048 90)
		(property "Reference" "C2758"
			(at 0 0 90)
			(layer "F.SilkS")
			(hide yes)
			(effects
				(font
					(size 1.27 1.27)
				)
			)
		)
		(property "Value" ""
			(at 0 0 90)
			(layer "F.Fab")
			(effects
				(font
					(size 1.27 1.27)
				)
			)
		)
		(duplicate_pad_numbers_are_jumpers no)
		(fp_line
			(start 0.7874 -0.4064)
			(end 0.7874 0.4064)
			(stroke
				(width 0.1524)
				(type default)
			)
			(layer "F.SilkS")
		)
		(fp_line
			(start -0.7874 -0.4064)
			(end 0.7874 -0.4064)
			(stroke
				(width 0.1524)
				(type default)
			)
			(layer "F.SilkS")
		)
		(fp_line
			(start 0.7874 0.4064)
			(end -0.7874 0.4064)
			(stroke
				(width 0.1524)
				(type default)
			)
			(layer "F.SilkS")
		)
		(fp_line
			(start -0.7874 0.4064)
			(end -0.7874 -0.4064)
			(stroke
				(width 0.1524)
				(type default)
			)
			(layer "F.SilkS")
		)
		(fp_line
			(start -0.12065 -0.305054)
			(end -0.12065 -0.2794)
			(stroke
				(width 0.1)
				(type default)
			)
			(layer "F.Fab")
		)
		(fp_line
			(start -0.67945 -0.305054)
			(end -0.12065 -0.305054)
			(stroke
				(width 0.1)
				(type default)
			)
			(layer "F.Fab")
		)
		(fp_line
			(start 0.67945 -0.3048)
			(end 0.67945 0.3048)
			(stroke
				(width 0.1)
				(type default)
			)
			(layer "F.Fab")
		)
		(fp_line
			(start 0.12065 -0.3048)
			(end 0.67945 -0.3048)
			(stroke
				(width 0.1)
				(type default)
			)
			(layer "F.Fab")
		)
		(fp_line
			(start 0.12065 -0.2794)
			(end 0.12065 -0.3048)
			(stroke
				(width 0.1)
				(type default)
			)
			(layer "F.Fab")
		)
		(fp_line
			(start -0.12065 -0.2794)
			(end 0.12065 -0.2794)
			(stroke
				(width 0.1)
				(type default)
			)
			(layer "F.Fab")
		)
		(fp_line
			(start 0.120396 0.2794)
			(end -0.12065 0.2794)
			(stroke
				(width 0.1)
				(type default)
			)
			(layer "F.Fab")
		)
		(fp_line
			(start -0.12065 0.2794)
			(end -0.12065 0.3048)
			(stroke
				(width 0.1)
				(type default)
			)
			(layer "F.Fab")
		)
		(fp_line
			(start 0.67945 0.3048)
			(end 0.120396 0.3048)
			(stroke
				(width 0.1)
				(type default)
			)
			(layer "F.Fab")
		)
		(fp_line
			(start 0.120396 0.3048)
			(end 0.120396 0.2794)
			(stroke
				(width 0.1)
				(type default)
			)
			(layer "F.Fab")
		)
		(fp_line
			(start -0.12065 0.3048)
			(end -0.67945 0.3048)
			(stroke
				(width 0.1)
				(type default)
			)
			(layer "F.Fab")
		)
		(fp_line
			(start -0.67945 0.3048)
			(end -0.67945 -0.305054)
			(stroke
				(width 0.1)
				(type default)
			)
			(layer "F.Fab")
		)
		(pad "1" smd circle
			(at -0.40005 0 90)
			(size 0 0)
			(layers "F.Cu" "F.Mask" "F.Paste")
			(net "GND")
		)
		(pad "2" smd circle
			(at 0.40005 0 90)
			(size 0 0)
			(layers "F.Cu" "F.Mask" "F.Paste")
			(net "P3V3_AUX")
		)
	)
	(footprint ""
		(layer "F.Cu")
		(at 140.442442 -250.070874 -90)
		(property "Reference" "R1278"
			(at 0 0 270)
			(layer "F.SilkS")
			(hide yes)
			(effects
				(font
					(size 1.27 1.27)
				)
			)
		)
		(property "Value" ""
			(at 0 0 270)
			(layer "F.Fab")
			(effects
				(font
					(size 1.27 1.27)
				)
			)
		)
		(duplicate_pad_numbers_are_jumpers no)
		(fp_line
			(start -0.7874 0.4064)
			(end -0.7874 -0.4064)
			(stroke
				(width 0.1524)
				(type default)
			)
			(layer "F.SilkS")
		)
		(fp_line
			(start 0.7874 0.4064)
			(end -0.7874 0.4064)
			(stroke
				(width 0.1524)
				(type default)
			)
			(layer "F.SilkS")
		)
		(fp_line
			(start -0.7874 -0.4064)
			(end 0.7874 -0.4064)
			(stroke
				(width 0.1524)
				(type default)
			)
			(layer "F.SilkS")
		)
		(fp_line
			(start 0.7874 -0.4064)
			(end 0.7874 0.4064)
			(stroke
				(width 0.1524)
				(type default)
			)
			(layer "F.SilkS")
		)
		(fp_line
			(start -0.67945 0.3048)
			(end -0.67945 -0.305054)
			(stroke
				(width 0.1)
				(type default)
			)
			(layer "F.Fab")
		)
		(fp_line
			(start -0.12065 0.3048)
			(end -0.67945 0.3048)
			(stroke
				(width 0.1)
				(type default)
			)
			(layer "F.Fab")
		)
		(fp_line
			(start 0.120396 0.3048)
			(end 0.120396 0.2794)
			(stroke
				(width 0.1)
				(type default)
			)
			(layer "F.Fab")
		)
		(fp_line
			(start 0.67945 0.3048)
			(end 0.120396 0.3048)
			(stroke
				(width 0.1)
				(type default)
			)
			(layer "F.Fab")
		)
		(fp_line
			(start -0.12065 0.2794)
			(end -0.12065 0.3048)
			(stroke
				(width 0.1)
				(type default)
			)
			(layer "F.Fab")
		)
		(fp_line
			(start 0.120396 0.2794)
			(end -0.12065 0.2794)
			(stroke
				(width 0.1)
				(type default)
			)
			(layer "F.Fab")
		)
		(fp_line
			(start -0.12065 -0.2794)
			(end 0.12065 -0.2794)
			(stroke
				(width 0.1)
				(type default)
			)
			(layer "F.Fab")
		)
		(fp_line
			(start 0.12065 -0.2794)
			(end 0.12065 -0.3048)
			(stroke
				(width 0.1)
				(type default)
			)
			(layer "F.Fab")
		)
		(fp_line
			(start 0.12065 -0.3048)
			(end 0.67945 -0.3048)
			(stroke
				(width 0.1)
				(type default)
			)
			(layer "F.Fab")
		)
		(fp_line
			(start 0.67945 -0.3048)
			(end 0.67945 0.3048)
			(stroke
				(width 0.1)
				(type default)
			)
			(layer "F.Fab")
		)
		(fp_line
			(start -0.67945 -0.305054)
			(end -0.12065 -0.305054)
			(stroke
				(width 0.1)
				(type default)
			)
			(layer "F.Fab")
		)
		(fp_line
			(start -0.12065 -0.305054)
			(end -0.12065 -0.2794)
			(stroke
				(width 0.1)
				(type default)
			)
			(layer "F.Fab")
		)
		(pad "1" smd circle
			(at -0.40005 0 270)
			(size 0 0)
			(layers "F.Cu" "F.Mask" "F.Paste")
			(net "PEX1_MODE_SEL9")
		)
		(pad "2" smd circle
			(at 0.40005 0 270)
			(size 0 0)
			(layers "F.Cu" "F.Mask" "F.Paste")
			(net "P1V8_PEX")
		)
	)
	(footprint ""
		(layer "F.Cu")
		(at 327.533 -217.297)
		(property "Reference" "R4164"
			(at 0 0 0)
			(layer "F.SilkS")
			(hide yes)
			(effects
				(font
					(size 1.27 1.27)
				)
			)
		)
		(property "Value" ""
			(at 0 0 0)
			(layer "F.Fab")
			(effects
				(font
					(size 1.27 1.27)
				)
			)
		)
		(duplicate_pad_numbers_are_jumpers no)
		(fp_line
			(start -0.7874 -0.4064)
			(end 0.7874 -0.4064)
			(stroke
				(width 0.1524)
				(type default)
			)
			(layer "F.SilkS")
		)
		(fp_line
			(start -0.7874 0.4064)
			(end -0.7874 -0.4064)
			(stroke
				(width 0.1524)
				(type default)
			)
			(layer "F.SilkS")
		)
		(fp_line
			(start 0.7874 -0.4064)
			(end 0.7874 0.4064)
			(stroke
				(width 0.1524)
				(type default)
			)
			(layer "F.SilkS")
		)
		(fp_line
			(start 0.7874 0.4064)
			(end -0.7874 0.4064)
			(stroke
				(width 0.1524)
				(type default)
			)
			(layer "F.SilkS")
		)
		(fp_line
			(start -0.67945 -0.305054)
			(end -0.12065 -0.305054)
			(stroke
				(width 0.1)
				(type default)
			)
			(layer "F.Fab")
		)
		(fp_line
			(start -0.67945 0.3048)
			(end -0.67945 -0.305054)
			(stroke
				(width 0.1)
				(type default)
			)
			(layer "F.Fab")
		)
		(fp_line
			(start -0.12065 -0.305054)
			(end -0.12065 -0.2794)
			(stroke
				(width 0.1)
				(type default)
			)
			(layer "F.Fab")
		)
		(fp_line
			(start -0.12065 -0.2794)
			(end 0.12065 -0.2794)
			(stroke
				(width 0.1)
				(type default)
			)
			(layer "F.Fab")
		)
		(fp_line
			(start -0.12065 0.2794)
			(end -0.12065 0.3048)
			(stroke
				(width 0.1)
				(type default)
			)
			(layer "F.Fab")
		)
		(fp_line
			(start -0.12065 0.3048)
			(end -0.67945 0.3048)
			(stroke
				(width 0.1)
				(type default)
			)
			(layer "F.Fab")
		)
		(fp_line
			(start 0.120396 0.2794)
			(end -0.12065 0.2794)
			(stroke
				(width 0.1)
				(type default)
			)
			(layer "F.Fab")
		)
		(fp_line
			(start 0.120396 0.3048)
			(end 0.120396 0.2794)
			(stroke
				(width 0.1)
				(type default)
			)
			(layer "F.Fab")
		)
		(fp_line
			(start 0.12065 -0.3048)
			(end 0.67945 -0.3048)
			(stroke
				(width 0.1)
				(type default)
			)
			(layer "F.Fab")
		)
		(fp_line
			(start 0.12065 -0.2794)
			(end 0.12065 -0.3048)
			(stroke
				(width 0.1)
				(type default)
			)
			(layer "F.Fab")
		)
		(fp_line
			(start 0.67945 -0.3048)
			(end 0.67945 0.3048)
			(stroke
				(width 0.1)
				(type default)
			)
			(layer "F.Fab")
		)
		(fp_line
			(start 0.67945 0.3048)
			(end 0.120396 0.3048)
			(stroke
				(width 0.1)
				(type default)
			)
			(layer "F.Fab")
		)
		(pad "1" smd circle
			(at -0.40005 0)
			(size 0 0)
			(layers "F.Cu" "F.Mask" "F.Paste")
			(net "PRSNT_NIC7_FPGA_R_N")
		)
		(pad "2" smd circle
			(at 0.40005 0)
			(size 0 0)
			(layers "F.Cu" "F.Mask" "F.Paste")
			(net "PRSNT_NIC7_FPGA_N")
		)
	)
	(footprint ""
		(layer "F.Cu")
		(at 18.668746 -149.313392 -90)
		(property "Reference" "U79"
			(at -0.191008 -2.516124 90)
			(unlocked yes)
			(layer "F.SilkS")
			(effects
				(font
					(size 0.7874 0.5842)
					(thickness 0.1524)
				)
			)
		)
		(property "Value" ""
			(at 0 0 270)
			(layer "F.Fab")
			(effects
				(font
					(size 1.27 1.27)
				)
			)
		)
		(duplicate_pad_numbers_are_jumpers no)
		(fp_line
			(start -1.500124 1.500124)
			(end -1.500124 1.004062)
			(stroke
				(width 0.1524)
				(type default)
			)
			(layer "F.SilkS")
		)
		(fp_line
			(start -1.004062 1.500124)
			(end -1.500124 1.500124)
			(stroke
				(width 0.1524)
				(type default)
			)
			(layer "F.SilkS")
		)
		(fp_line
			(start 1.500124 1.500124)
			(end 1.004062 1.500124)
			(stroke
				(width 0.1524)
				(type default)
			)
			(layer "F.SilkS")
		)
		(fp_line
			(start 1.500124 1.004062)
			(end 1.500124 1.500124)
			(stroke
				(width 0.1524)
				(type default)
			)
			(layer "F.SilkS")
		)
		(fp_line
			(start -1.500124 -1.004062)
			(end -1.500124 -1.500124)
			(stroke
				(width 0.1524)
				(type default)
			)
			(layer "F.SilkS")
		)
		(fp_line
			(start -1.500124 -1.500124)
			(end -1.004062 -1.500124)
			(stroke
				(width 0.1524)
				(type default)
			)
			(layer "F.SilkS")
		)
		(fp_line
			(start 1.004062 -1.500124)
			(end 1.500124 -1.500124)
			(stroke
				(width 0.1524)
				(type default)
			)
			(layer "F.SilkS")
		)
		(fp_line
			(start 1.500124 -1.500124)
			(end 1.500124 -1.004062)
			(stroke
				(width 0.1524)
				(type default)
			)
			(layer "F.SilkS")
		)
		(fp_poly
			(pts
				(xy -1.976628 -2.091944) (xy -2.695194 -1.373378) (xy -1.617472 -1.014222)
			)
			(stroke
				(width 0)
				(type default)
			)
			(fill yes)
			(layer "F.SilkS")
		)
		(fp_line
			(start -1.500124 1.500124)
			(end -1.500124 -1.500124)
			(stroke
				(width 0.1)
				(type default)
			)
			(layer "F.Fab")
		)
		(fp_line
			(start 1.500124 1.500124)
			(end -1.500124 1.500124)
			(stroke
				(width 0.1)
				(type default)
			)
			(layer "F.Fab")
		)
		(fp_line
			(start -1.500124 -1.500124)
			(end 1.500124 -1.500124)
			(stroke
				(width 0.1)
				(type default)
			)
			(layer "F.Fab")
		)
		(fp_line
			(start 1.500124 -1.500124)
			(end 1.500124 1.500124)
			(stroke
				(width 0.1)
				(type default)
			)
			(layer "F.Fab")
		)
		(fp_poly
			(pts
				(xy -2.847848 -1.258062) (xy -2.847848 -0.242062) (xy -1.831848 -0.750062)
			)
			(stroke
				(width 0)
				(type default)
			)
			(fill yes)
			(layer "F.Fab")
		)
		(pad "1" smd rect
			(at -1.400048 -0.750062 180)
			(size 0.2286 0.6096)
			(layers "F.Cu" "F.Mask" "F.Paste")
			(net "NIC0_ADC_A1")
		)
		(pad "2" smd rect
			(at -1.400048 -0.249936 180)
			(size 0.2286 0.6096)
			(layers "F.Cu" "F.Mask" "F.Paste")
			(net "NIC0_ADC_A0")
		)
		(pad "3" smd rect
			(at -1.400048 0.249936 180)
			(size 0.2286 0.6096)
			(layers "F.Cu" "F.Mask" "F.Paste")
			(net "NIC0_ADC_ALERT_N")
		)
		(pad "4" smd rect
			(at -1.400048 0.750062 180)
			(size 0.2286 0.6096)
			(layers "F.Cu" "F.Mask" "F.Paste")
			(net "SMB_NIC0_ADC_SDA")
		)
		(pad "5" smd rect
			(at -0.750062 1.400048 270)
			(size 0.2286 0.6096)
			(layers "F.Cu" "F.Mask" "F.Paste")
			(net "SMB_NIC0_ADC_SCL")
		)
		(pad "6" smd rect
			(at -0.249936 1.400048 270)
			(size 0.2286 0.6096)
			(layers "F.Cu" "F.Mask" "F.Paste")
			(net "Net_8666")
		)
		(pad "7" smd rect
			(at 0.249936 1.400048 270)
			(size 0.2286 0.6096)
			(layers "F.Cu" "F.Mask" "F.Paste")
			(net "Net_8665")
		)
		(pad "8" smd rect
			(at 0.750062 1.400048 270)
			(size 0.2286 0.6096)
			(layers "F.Cu" "F.Mask" "F.Paste")
			(net "Net_8664")
		)
		(pad "9" smd rect
			(at 1.400048 0.750062 180)
			(size 0.2286 0.6096)
			(layers "F.Cu" "F.Mask" "F.Paste")
			(net "P3V3_AUX")
		)
		(pad "10" smd rect
			(at 1.400048 0.249936 180)
			(size 0.2286 0.6096)
			(layers "F.Cu" "F.Mask" "F.Paste")
			(net "GND")
		)
		(pad "11" smd rect
			(at 1.400048 -0.249936 180)
			(size 0.2286 0.6096)
			(layers "F.Cu" "F.Mask" "F.Paste")
			(net "P12V_NIC0_R")
		)
		(pad "12" smd rect
			(at 1.400048 -0.750062 180)
			(size 0.2286 0.6096)
			(layers "F.Cu" "F.Mask" "F.Paste")
			(net "P12V_NIC0_VIN_N")
		)
		(pad "13" smd rect
			(at 0.750062 -1.400048 270)
			(size 0.2286 0.6096)
			(layers "F.Cu" "F.Mask" "F.Paste")
			(net "P12V_NIC0_VIN_P")
		)
		(pad "14" smd rect
			(at 0.249936 -1.400048 270)
			(size 0.2286 0.6096)
			(layers "F.Cu" "F.Mask" "F.Paste")
			(net "Net_8663")
		)
		(pad "15" smd rect
			(at -0.249936 -1.400048 270)
			(size 0.2286 0.6096)
			(layers "F.Cu" "F.Mask" "F.Paste")
			(net "Net_8662")
		)
		(pad "16" smd rect
			(at -0.750062 -1.400048 270)
			(size 0.2286 0.6096)
			(layers "F.Cu" "F.Mask" "F.Paste")
			(net "Net_8661")
		)
		(pad "TH" smd rect
			(at 0 0 270)
			(size 1.7018 1.7018)
			(layers "F.Cu" "F.Mask" "F.Paste")
			(net "GND")
		)
		(zone
			(layer "F.Cu")
			(hatch none 0.5)
			(connect_pads
				(clearance 0)
			)
			(min_thickness 0.25)
			(keepout
				(tracks not_allowed)
				(vias allowed)
				(pads allowed)
				(copperpour not_allowed)
				(footprints allowed)
			)
			(placement
				(enabled no)
				(sheetname "")
			)
			(fill
				(thermal_gap 0.5)
				(thermal_bridge_width 0.5)
				(island_removal_mode 0)
			)
			(polygon
				(pts
					(xy 18.694146 -150.35784) (xy 19.713194 -150.35784) (xy 19.713194 -148.268944) (xy 17.624298 -148.268944)
					(xy 17.624298 -150.35784) (xy 18.668746 -150.35784) (xy 18.668746 -150.215092) (xy 17.767046 -150.215092)
					(xy 17.767046 -148.411692) (xy 19.570446 -148.411692) (xy 19.570446 -150.215092) (xy 18.694146 -150.215092)
				)
			)
		)
	)
)
